FILE_TYPE = CONNECTIVITY;
{Allegro Design Entry HDL 16.6-p007 (v16-6-112F) 10/10/2012}
"PAGE_NUMBER" = 185;
0"NC";
1"P3V3\g";
2"P3V3_STBY\g";
3"P3V3_STBY\g";
4"GND\g";
5"GND\g";
6"P3V3\g";
7"P3V3\g";
8"GND\g";
9"P3V3\g";
10"GND\g";
11"P3V3\g";
12"GND\g";
13"GND\g";
14"GND\g";
15"GND\g";
16"GND\g";
17"GND\g";
18"GND\g";
19"GND\g";
20"GND\g";
21"GND\g";
22"GND\g";
23"P3V3\g";
24"P3V3\g";
25"GND\g";
26"GND\g";
27"GND\g";
28"GND\g";
29"P3V3_STBY\g";
30"GND\g";
31"GND\g";
32"P3V3_STBY\g";
33"GND\g";
34"GND\g";
35"P3V3\g";
36"GND\g";
37"GND\g";
38"GND\g";
39"SMB_M2_SCL";
40"TP_LED_M2_ACT_N";
41"P3E_PCH_M2_SATA6G_TX_R_DN";
42"SATA6G_S0_RX_DP";
43"SATA6G_S0_RX_DN";
44"PD_SMB_M2_EN";
45"SMB_M2_ALT_R_N";
46"P1V8_M2";
47"SMB_OCP_LAN_STBY_LVC3_SDA";
48"P1V8_M2";
49"SATA6G_S0_TX_DN";
50"P3E_PCH_RX_0_DP";
51"NC_M2<0>";
52"NC_M2<1>";
53"TP_M2_32M_SUSCLK";
54"FM_PE_M2_WAKE_N";
55"SMB_M2_SDA_R";
56"P3E_PCH_M2_TX_DN<3>";
57"P3E_PCH_M2_TX_C_DN<3>";
58"P3E_PCH_M2_TX_DP<3>";
59"P3E_PCH_M2_TX_C_DP<3>";
60"P3E_PCH_M2_RX_DN<3>";
61"P3E_PCH_M2_RX_DP<3>";
62"P3E_PCH_M2_TX_C_DP<2>";
63"P3E_PCH_M2_TX_DN<2>";
64"P3E_PCH_M2_TX_C_DN<2>";
65"P3E_PCH_M2_SATA6G_RX_R_DP";
66"P3E_PCH_M2_SATA6G_TX_R_DN";
67"P3E_PCH_M2_SATA6G_TX_R_DP";
68"CLK_100M_M2_DN";
69"P3E_PCH_M2_SATA6G_RX_R_DN";
70"P3E_PCH_M2_TX_C_DN<1>";
71"FM_SSATA_PCIE_M2_SEL";
72"FM_M2_SSD_PEDET";
73"P3E_PCH_TX_0_DN";
74"CLK_100M_M2_DP";
75"SMB_M2_ALT_N";
76"IRQ_MEZZ_LAN_ALERT_N";
77"P1V8_M2";
78"SMB_M2_ALT_N";
79"SMB_M2_SCL_R";
80"SMB_M2_SDA";
81"P3E_PCH_M2_RX_DN<2>";
82"P3E_PCH_M2_RX_DP<2>";
83"P3E_PCH_M2_RX_DN<1>";
84"P3E_PCH_M2_RX_DP<1>";
85"P3E_PCH_M2_TX_C_DP<1>";
86"RST_PCIE_M2_DEV_IC_N";
87"PU_M2_CLK_REQ_N";
88"SMB_M2_ALT_N";
89"TP_M2_DEVSLP";
90"P3E_PCH_TX_0_DP";
91"P3E_PCH_RX_0_DN";
92"SMB_M2_SCL";
93"SMB_M2_SDA";
94"FM_M2_DET_LVC3";
95"P1V8_M2";
96"SMB_M2_SDA";
97"SMB_M2_SCL";
98"VREF_LMV431_1V42";
99"SMB_OCP_LAN_STBY_LVC3_SCL";
100"P3E_PCH_M2_TX_DP<2>";
101"P3E_PCH_M2_TX_DN<1>";
102"P3E_PCH_M2_TX_DP<1>";
103"SATA6G_S0_TX_DP";
104"P3E_PCH_M2_SATA6G_TX_R_DP";
105"P3E_PCH_M2_SATA6G_RX_R_DN";
106"P3E_PCH_M2_SATA6G_RX_R_DP";
%"RES"
"1","(-2600,950)","0","mstr_discrete","I105";
;
CDS_SEC"1"
WATTAGE"1/16W"
PACK_TYPE"0402"
MATERIAL"CHIP"
PART_NUMBER"G21497-005"
LOCATION"R8F18"
VALUE"0.0"
TOLERANCE"5%"
GROUP"M2_PCIE"
CDS_LOCATION"R8F18"
SEC"1"
CDS_LIB"mstr_discrete"
SEC_TYPE"0402"
ROOM"M_2"
BOM_COST"ST_FLASH";
"B"
$PN"2"106;
"A"
$PN"1"50;
%"RES"
"1","(-2575,500)","0","mstr_discrete","I106";
;
CDS_SEC"1"
MATERIAL"CHIP"
VALUE"0.0"
LOCATION"R8F21"
WATTAGE"1/16W"
TOLERANCE"5%"
PACK_TYPE"0402"
PART_NUMBER"G21497-005"
GROUP"M2_PCIE"
CDS_LOCATION"R8F21"
CDS_LIB"mstr_discrete"
SEC_TYPE"0402"
SEC"1"
BOM_COST"ST_FLASH"
ROOM"M_2";
"B"
$PN"2"105;
"A"
$PN"1"91;
%"TTL1G07_A"
"1","(-5150,2500)","0","mstr_ttl","I110";
;
CDS_SEC"1"
CDS_LOCATION"U2P1"
VALUE"74LVC1G07"
MATERIAL"IC"
LOCATION"U2P1"
POWER_GROUP"VCC=P3V3_STBY;GND=GND"
PART_NUMBER"C88419-001"
ROOM"M_2"
BOM_COST"ST_FLASH"
SEC_TYPE"SOP"
PACK_TYPE"SOP"
CDS_LIB"mstr_ttl"
SEC"1";
"Y"
$PN"4"94;
"A"
$PN"2"72;
%"RES"
"2","(-5500,2700)","0","mstr_discrete","I111";
;
CDS_SEC"1"
CDS_LOCATION"R2P15"
VALUE"10.0K"
TOLERANCE"1%"
MATERIAL"CHIP"
PACK_TYPE"0402"
PART_NUMBER"G21796-016"
LOCATION"R2P15"
WATTAGE"1/16W"
CDS_LIB"mstr_discrete"
SEC"1"
ROOM"M_2"
SEC_TYPE"0402"
BOM_COST"ST_FLASH";
"A"
$PN"1"1;
"B"
$PN"2"72;
%"P3V3"
"1","(-5500,2900)","0","mstr_symbols","I112";
;
HDL_POWER"P3V3"
BODY_TYPE"PLUMBING"
CDS_LIB"mstr_symbols"
SIZE"1B"
VOLTAGE"3.3V";
"G\NAC"1;
%"RES"
"2","(-4400,2800)","0","mstr_discrete","I113";
;
CDS_SEC"1"
CDS_LOCATION"R2P16"
LOCATION"R2P16"
VALUE"10.0K"
MATERIAL"CHIP"
PACK_TYPE"0402"
TOLERANCE"1%"
WATTAGE"1/16W"
PART_NUMBER"G21796-016"
CDS_LIB"mstr_discrete"
SEC"1"
ROOM"M_2"
SEC_TYPE"0402"
BOM_COST"ST_FLASH";
"A"
$PN"1"2;
"B"
$PN"2"94;
%"P3V3_STBY"
"1","(-4400,3000)","0","mstr_symbols","I114";
;
HDL_POWER"P3V3_STBY"
VOLTAGE"3.3V"
CDS_LIB"mstr_symbols"
BODY_TYPE"PLUMBING"
SIZE"1B";
"G\NAC"2;
%"RES"
"1","(-4250,2500)","0","mstr_discrete","I115";
;
CDS_SEC"1"
CDS_LOCATION"R2P14"
PART_NUMBER"G21497-005"
LOCATION"R2P14"
MATERIAL"CHIP"
WATTAGE"1/16W"
VALUE"0.0"
TOLERANCE"5%"
PACK_TYPE"0402"
CDS_LIB"mstr_discrete"
SEC"1"
SEC_TYPE"0402"
ROOM"M_2"
BOM_COST"ST_FLASH";
"B"
$PN"2"71;
"A"
$PN"1"94;
%"CAP_A"
"1","(-4500,1975)","0","dev_discrete","I117";
;
CDS_LOCATION"C2P9"
PACK_TYPE"0402V"
MATERIAL"X7R"
TOLERANCE"10%"
VOLTAGE"16V"
PART_NUMBER"A36096-030"
LOCATION"C2P9"
VALUE"0.1UF"
BOM_COST"SD_FLASH"
ROOM"M_2"
CDS_SEC"1"
SEC"1"
SEC_TYPE"0402V"
CDS_LIB"dev_discrete";
"B"
$PN"2"4;
"A"
$PN"1"3;
%"P3V3_STBY"
"1","(-4500,2200)","0","mstr_symbols","I118";
;
SIZE"1B"
BODY_TYPE"PLUMBING"
CDS_LIB"mstr_symbols"
VOLTAGE"3.3V"
HDL_POWER"P3V3_STBY";
"G\NAC"3;
%"GND"
"1","(-4500,1750)","0","mstr_symbols","I119";
;
HDL_POWER"GND"
CDS_LIB"mstr_symbols"
VOLTAGE"0.0V"
SIZE"1B"
BODY_TYPE"PLUMBING";
"A\NAC"4;
%"CAP_A"
"1","(-4250,4575)","0","dev_discrete","I120";
;
MATERIAL"X7R"
VOLTAGE"16V"
PACK_TYPE"0402V"
TOLERANCE"10%"
VALUE"0.1UF"
LOCATION"C2T29"
PART_NUMBER"A36096-030"
CDS_LIB"dev_discrete"
CDS_LOCATION"C2T29"
SEC"1"
CDS_SEC"1"
ROOM"M_2"
SEC_TYPE"0402V"
BOM_COST"SD_FLASH";
"B"
$PN"2"5;
"A"
$PN"1"6;
%"GND"
"1","(-4250,4350)","0","mstr_symbols","I122";
;
BODY_TYPE"PLUMBING"
CDS_LIB"mstr_symbols"
VOLTAGE"0.0V"
HDL_POWER"GND"
SIZE"1B";
"A\NAC"5;
%"CAP_A"
"1","(-4000,4575)","0","dev_discrete","I123";
;
VALUE"0.1UF"
LOCATION"C2T26"
MATERIAL"X7R"
VOLTAGE"16V"
PACK_TYPE"0402V"
TOLERANCE"10%"
PART_NUMBER"A36096-030"
CDS_LIB"dev_discrete"
CDS_LOCATION"C2T26"
ROOM"M_2"
BOM_COST"SD_FLASH"
CDS_SEC"1"
SEC"1"
SEC_TYPE"0402V";
"B"
$PN"2"5;
"A"
$PN"1"6;
%"CAP_A"
"1","(-3750,4575)","0","dev_discrete","I124";
;
PART_NUMBER"A36096-030"
VALUE"0.1UF"
TOLERANCE"10%"
PACK_TYPE"0402V"
VOLTAGE"16V"
LOCATION"C2T21"
MATERIAL"X7R"
CDS_LIB"dev_discrete"
CDS_LOCATION"C2T21"
ROOM"M_2"
BOM_COST"SD_FLASH"
CDS_SEC"1"
SEC"1"
SEC_TYPE"0402V";
"B"
$PN"2"5;
"A"
$PN"1"6;
%"P3V3"
"1","(-4250,4800)","0","mstr_symbols","I125";
;
HDL_POWER"P3V3"
BODY_TYPE"PLUMBING"
VOLTAGE"3.3V"
CDS_LIB"mstr_symbols"
SIZE"1B";
"G\NAC"6;
%"CAP_A"
"1","(-2425,4575)","0","dev_discrete","I126";
;
PART_NUMBER"A36096-030"
PACK_TYPE"0402V"
MATERIAL"X7R"
TOLERANCE"10%"
VALUE"0.1UF"
VOLTAGE"16V"
LOCATION"C2T16"
CDS_LIB"dev_discrete"
CDS_LOCATION"C2T16"
CDS_SEC"1"
SEC_TYPE"0402V"
SEC"1"
ROOM"M_2"
BOM_COST"SD_FLASH";
"B"
$PN"2"8;
"A"
$PN"1"7;
%"CAP_A"
"1","(-2675,4575)","0","dev_discrete","I127";
;
MATERIAL"X7R"
VOLTAGE"16V"
PACK_TYPE"0402V"
TOLERANCE"10%"
VALUE"0.1UF"
PART_NUMBER"A36096-030"
LOCATION"C2T15"
CDS_LIB"dev_discrete"
CDS_LOCATION"C2T15"
CDS_SEC"1"
ROOM"M_2"
BOM_COST"SD_FLASH"
SEC"1"
SEC_TYPE"0402V";
"B"
$PN"2"8;
"A"
$PN"1"7;
%"P3V3"
"1","(-2925,4800)","0","mstr_symbols","I128";
;
HDL_POWER"P3V3"
BODY_TYPE"PLUMBING"
VOLTAGE"3.3V"
SIZE"1B"
CDS_LIB"mstr_symbols";
"G\NAC"7;
%"CAP_A"
"1","(-2925,4575)","0","dev_discrete","I129";
;
PACK_TYPE"0402V"
MATERIAL"X7R"
VOLTAGE"16V"
TOLERANCE"10%"
VALUE"0.1UF"
LOCATION"C2T24"
PART_NUMBER"A36096-030"
CDS_LIB"dev_discrete"
CDS_LOCATION"C2T24"
CDS_SEC"1"
BOM_COST"SD_FLASH"
ROOM"M_2"
SEC"1"
SEC_TYPE"0402V";
"B"
$PN"2"8;
"A"
$PN"1"7;
%"GND"
"1","(-2925,4350)","0","mstr_symbols","I130";
;
VOLTAGE"0.0V"
BODY_TYPE"PLUMBING"
CDS_LIB"mstr_symbols"
SIZE"1B"
HDL_POWER"GND";
"A\NAC"8;
%"CAP_A"
"1","(-950,4575)","0","dev_discrete","I131";
;
VALUE"0.1UF"
TOLERANCE"10%"
PACK_TYPE"0402V"
VOLTAGE"16V"
MATERIAL"X7R"
LOCATION"C2T2"
PART_NUMBER"A36096-030"
BOM_COST"SD_FLASH"
CDS_LOCATION"C2T2"
CDS_SEC"1"
SEC"1"
SEC_TYPE"0402V"
ROOM"M_2"
CDS_LIB"dev_discrete";
"B"
$PN"2"10;
"A"
$PN"1"9;
%"CAP_A"
"1","(-1200,4575)","0","dev_discrete","I132";
;
VALUE"0.1UF"
PART_NUMBER"A36096-030"
TOLERANCE"10%"
PACK_TYPE"0402V"
VOLTAGE"16V"
MATERIAL"X7R"
LOCATION"C2T4"
BOM_COST"SD_FLASH"
SEC_TYPE"0402V"
SEC"1"
CDS_SEC"1"
ROOM"M_2"
CDS_LOCATION"C2T4"
CDS_LIB"dev_discrete";
"B"
$PN"2"10;
"A"
$PN"1"9;
%"P3V3"
"1","(-1450,4800)","0","mstr_symbols","I133";
;
SIZE"1B"
BODY_TYPE"PLUMBING"
CDS_LIB"mstr_symbols"
VOLTAGE"3.3V"
HDL_POWER"P3V3";
"G\NAC"9;
%"GND"
"1","(-1450,4350)","0","mstr_symbols","I134";
;
HDL_POWER"GND"
CDS_LIB"mstr_symbols"
SIZE"1B"
VOLTAGE"0.0V"
BODY_TYPE"PLUMBING";
"A\NAC"10;
%"CAP_A"
"1","(-1450,4575)","0","dev_discrete","I135";
;
PACK_TYPE"0402V"
PART_NUMBER"A36096-030"
TOLERANCE"10%"
LOCATION"C2T5"
VALUE"0.1UF"
VOLTAGE"16V"
MATERIAL"X7R"
BOM_COST"SD_FLASH"
SEC_TYPE"0402V"
SEC"1"
CDS_SEC"1"
ROOM"M_2"
CDS_LOCATION"C2T5"
CDS_LIB"dev_discrete";
"B"
$PN"2"10;
"A"
$PN"1"9;
%"RES"
"2","(-8000,3500)","0","mstr_discrete","I136";
;
CDS_SEC"1"
CDS_LOCATION"R8F36"
PART_NUMBER"G21796-016"
MATERIAL"CHIP"
VALUE"10.0K"
LOCATION"R8F36"
TOLERANCE"1%"
WATTAGE"1/16W"
PACK_TYPE"0402"
BOM_COST"ST_FLASH"
SEC"1"
SEC_TYPE"0402"
ROOM"M_2"
CDS_LIB"mstr_discrete";
"A"
$PN"1"11;
"B"
$PN"2"87;
%"P3V3"
"1","(-8000,3700)","0","mstr_symbols","I137";
;
SIZE"1B"
CDS_LIB"mstr_symbols"
VOLTAGE"3.3V"
BODY_TYPE"PLUMBING"
HDL_POWER"P3V3";
"G\NAC"11;
%"CAP_A"
"1","(-2600,2100)","1","dev_discrete","I138";
;
CDS_SEC"1"
CDS_LOCATION"C8F6"
GROUP"M2_SATA"
PART_NUMBER"A36096-045"
VOLTAGE"25V"
TOLERANCE"10%"
VALUE"0.01UF"
PACK_TYPE"0402V"
MATERIAL"X7R"
LOCATION"C8F6"
SEC"1"
SEC_TYPE"0402V"
CDS_LIB"dev_discrete";
"B"
$PN"2"104;
"A"
$PN"1"103;
%"CAP_A"
"1","(-2600,1600)","1","dev_discrete","I139";
;
CDS_SEC"1"
CDS_LOCATION"C8F11"
VOLTAGE"25V"
LOCATION"C8F11"
VALUE"0.01UF"
TOLERANCE"10%"
PACK_TYPE"0402V"
MATERIAL"X7R"
PART_NUMBER"A36096-045"
GROUP"M2_SATA"
CDS_LIB"dev_discrete"
SEC_TYPE"0402V"
SEC"1";
"B"
$PN"2"41;
"A"
$PN"1"49;
%"CAP"
"2","(-2600,1375)","0","mstr_discrete","I140";
;
CDS_SEC"1"
PACK_TYPE"0402"
VOLTAGE"16V"
PART_NUMBER"A36096-155"
VALUE"0.22UF"
MATERIAL"X7R"
TOLERANCE"10%"
LOCATION"C8F12"
GROUP"M2_PCIE"
SEC"1"
SEC_TYPE"0402"
BOM_COST"ST_FLASH"
ROOM"M_2"
CDS_LIB"mstr_discrete"
CDS_LOCATION"C8F12";
"A"
$PN"1"73;
"B"
$PN"2"41;
%"CAP_A"
"1","(-2600,1175)","1","dev_discrete","I141";
;
CDS_SEC"1"
CDS_LOCATION"C8F13"
PACK_TYPE"0402V"
TOLERANCE"10%"
VALUE"0.01UF"
PART_NUMBER"A36096-045"
MATERIAL"X7R"
VOLTAGE"25V"
GROUP"M2_SATA"
LOCATION"C8F13"
SEC"1"
SEC_TYPE"0402V"
CDS_LIB"dev_discrete";
"B"
$PN"2"106;
"A"
$PN"1"42;
%"CAP_A"
"1","(-2575,750)","1","dev_discrete","I142";
;
CDS_SEC"1"
CDS_LOCATION"C8F15"
PACK_TYPE"0402V"
VALUE"0.01UF"
VOLTAGE"25V"
TOLERANCE"10%"
MATERIAL"X7R"
LOCATION"C8F15"
PART_NUMBER"A36096-045"
GROUP"M2_SATA"
SEC"1"
SEC_TYPE"0402V"
CDS_LIB"dev_discrete";
"B"
$PN"2"105;
"A"
$PN"1"43;
%"SKT-MINI67P-41-GP"
"1","(-6450,3650)","0","w_hdl","I143";
;
CDS_SEC"1"
CDS_LOCATION"J8F1"
VALUE"SKT-MINI67P-41-GP"
LOCATION"J8F1"
CDS_LMAN_SYM_OUTLINE"-150,1050,150,-1050"
CDS_LIB"w_hdl"
PART_NUMBER"062.10003.0B21"
SEC_TYPE"SOCKET-G4"
SEC"1"
PACK_TYPE"SOCKET-G4";
"NP2"
$PN"NP2"0;
"NP1"
$PN"NP1"0;
"77"
$PN"77"12;
"76"
$PN"76"13;
"74"
$PN"74"24;
"72"
$PN"72"24;
"70"
$PN"70"24;
"68"
$PN"68"53;
"58"
$PN"58"0;
"56"
$PN"56"0;
"54"
$PN"54"54;
"52"
$PN"52"87;
"50"
$PN"50"86;
"48"
$PN"48"0;
"46"
$PN"46"0;
"44"
$PN"44"88;
"42"
$PN"42"80;
"40"
$PN"40"39;
"38"
$PN"38"89;
"36"
$PN"36"0;
"34"
$PN"34"0;
"32"
$PN"32"0;
"30"
$PN"30"0;
"28"
$PN"28"0;
"26"
$PN"26"0;
"24"
$PN"24"0;
"22"
$PN"22"0;
"20"
$PN"20"0;
"18"
$PN"18"23;
"16"
$PN"16"23;
"14"
$PN"14"23;
"12"
$PN"12"23;
"10"
$PN"10"40;
"8"
$PN"8"52;
"6"
$PN"6"51;
"4"
$PN"4"23;
"2"
$PN"2"23;
"75"
$PN"75"12;
"73"
$PN"73"12;
"71"
$PN"71"12;
"69"
$PN"69"72;
"67"
$PN"67"0;
"57"
$PN"57"22;
"55"
$PN"55"74;
"53"
$PN"53"68;
"51"
$PN"51"21;
"49"
$PN"49"67;
"47"
$PN"47"66;
"45"
$PN"45"20;
"43"
$PN"43"69;
"41"
$PN"41"65;
"39"
$PN"39"19;
"37"
$PN"37"85;
"35"
$PN"35"70;
"33"
$PN"33"18;
"31"
$PN"31"84;
"29"
$PN"29"83;
"27"
$PN"27"17;
"25"
$PN"25"62;
"23"
$PN"23"64;
"21"
$PN"21"16;
"19"
$PN"19"82;
"17"
$PN"17"81;
"15"
$PN"15"15;
"13"
$PN"13"59;
"11"
$PN"11"57;
"9"
$PN"9"14;
"7"
$PN"7"61;
"5"
$PN"5"60;
"3"
$PN"3"13;
"1"
$PN"1"13;
%"GND"
"1","(-6000,2550)","0","mstr_symbols","I144";
;
HDL_POWER"GND"
VOLTAGE"0.0V"
CDS_LIB"mstr_symbols"
SIZE"1B"
BODY_TYPE"PLUMBING";
"A\NAC"12;
%"GND"
"1","(-5900,4550)","0","mstr_symbols","I145";
;
HDL_POWER"GND"
VOLTAGE"0.0V"
CDS_LIB"mstr_symbols"
SIZE"1B"
BODY_TYPE"PLUMBING";
"A\NAC"13;
%"GND"
"1","(-5950,4300)","1","mstr_symbols","I146";
;
HDL_POWER"GND"
VOLTAGE"0.0V"
CDS_LIB"mstr_symbols"
SIZE"1B"
BODY_TYPE"PLUMBING";
"A\NAC"14;
%"GND"
"1","(-5950,4150)","1","mstr_symbols","I147";
;
HDL_POWER"GND"
VOLTAGE"0.0V"
CDS_LIB"mstr_symbols"
SIZE"1B"
BODY_TYPE"PLUMBING";
"A\NAC"15;
%"GND"
"1","(-5950,4000)","1","mstr_symbols","I148";
;
HDL_POWER"GND"
VOLTAGE"0.0V"
CDS_LIB"mstr_symbols"
SIZE"1B"
BODY_TYPE"PLUMBING";
"A\NAC"16;
%"GND"
"1","(-5950,3850)","1","mstr_symbols","I149";
;
HDL_POWER"GND"
VOLTAGE"0.0V"
CDS_LIB"mstr_symbols"
SIZE"1B"
BODY_TYPE"PLUMBING";
"A\NAC"17;
%"GND"
"1","(-5950,3700)","1","mstr_symbols","I150";
;
BODY_TYPE"PLUMBING"
SIZE"1B"
CDS_LIB"mstr_symbols"
VOLTAGE"0.0V"
HDL_POWER"GND";
"A\NAC"18;
%"GND"
"1","(-5950,3550)","1","mstr_symbols","I151";
;
BODY_TYPE"PLUMBING"
SIZE"1B"
CDS_LIB"mstr_symbols"
VOLTAGE"0.0V"
HDL_POWER"GND";
"A\NAC"19;
%"GND"
"1","(-5950,3400)","1","mstr_symbols","I152";
;
BODY_TYPE"PLUMBING"
SIZE"1B"
CDS_LIB"mstr_symbols"
VOLTAGE"0.0V"
HDL_POWER"GND";
"A\NAC"20;
%"GND"
"1","(-5950,3250)","1","mstr_symbols","I153";
;
BODY_TYPE"PLUMBING"
SIZE"1B"
CDS_LIB"mstr_symbols"
VOLTAGE"0.0V"
HDL_POWER"GND";
"A\NAC"21;
%"GND"
"1","(-5950,3100)","1","mstr_symbols","I154";
;
HDL_POWER"GND"
VOLTAGE"0.0V"
CDS_LIB"mstr_symbols"
SIZE"1B"
BODY_TYPE"PLUMBING";
"A\NAC"22;
%"P3V3"
"1","(-7550,4550)","0","mstr_symbols","I155";
;
HDL_POWER"P3V3"
BODY_TYPE"PLUMBING"
CDS_LIB"mstr_symbols"
SIZE"1B"
VOLTAGE"3.3V";
"G\NAC"23;
%"P3V3"
"1","(-7550,3000)","0","mstr_symbols","I156";
;
VOLTAGE"3.3V"
SIZE"1B"
CDS_LIB"mstr_symbols"
BODY_TYPE"PLUMBING"
HDL_POWER"P3V3";
"G\NAC"24;
%"CAP"
"2","(-4850,3650)","0","mstr_discrete","I167";
;
CDS_SEC"1"
VALUE"0.22UF"
LOCATION"C2T11"
PACK_TYPE"0402"
VOLTAGE"16V"
MATERIAL"X7R"
TOLERANCE"10%"
PART_NUMBER"A36096-155"
ROOM"M_2"
BOM_COST"ST_FLASH"
SEC"1"
SEC_TYPE"0402"
CDS_LIB"mstr_discrete"
CDS_LOCATION"C2T11";
"A"
$PN"1"70;
"B"
$PN"2"101;
%"CAP"
"2","(-4850,3600)","0","mstr_discrete","I168";
;
CDS_SEC"1"
LOCATION"C2T10"
MATERIAL"X7R"
PACK_TYPE"0402"
PART_NUMBER"A36096-155"
VOLTAGE"16V"
VALUE"0.22UF"
TOLERANCE"10%"
CDS_LOCATION"C2T10"
CDS_LIB"mstr_discrete"
SEC_TYPE"0402"
SEC"1"
BOM_COST"ST_FLASH"
ROOM"M_2";
"A"
$PN"1"85;
"B"
$PN"2"102;
%"CAP"
"2","(-4850,3950)","0","mstr_discrete","I171";
;
PART_NUMBER"A36096-155"
PACK_TYPE"0402"
LOCATION"C2T14"
VOLTAGE"16V"
MATERIAL"X7R"
TOLERANCE"10%"
VALUE"0.22UF"
CDS_SEC"1"
SEC"1"
SEC_TYPE"0402"
ROOM"M_2"
BOM_COST"ST_FLASH"
CDS_LIB"mstr_discrete"
CDS_LOCATION"C2T14";
"A"
$PN"1"64;
"B"
$PN"2"63;
%"CAP"
"2","(-4850,3900)","0","mstr_discrete","I172";
;
VOLTAGE"16V"
LOCATION"C2T13"
TOLERANCE"10%"
MATERIAL"X7R"
PACK_TYPE"0402"
PART_NUMBER"A36096-155"
VALUE"0.22UF"
CDS_LOCATION"C2T13"
CDS_LIB"mstr_discrete"
BOM_COST"ST_FLASH"
ROOM"M_2"
SEC_TYPE"0402"
SEC"1"
CDS_SEC"1";
"A"
$PN"1"62;
"B"
$PN"2"100;
%"CAP"
"2","(-4850,4200)","0","mstr_discrete","I179";
;
PART_NUMBER"A36096-155"
TOLERANCE"10%"
MATERIAL"X7R"
VOLTAGE"16V"
PACK_TYPE"0402"
LOCATION"C2T20"
VALUE"0.22UF"
CDS_LOCATION"C2T20"
CDS_LIB"mstr_discrete"
SEC_TYPE"0402"
SEC"1"
ROOM"M_2"
BOM_COST"ST_FLASH"
CDS_SEC"1";
"A"
$PN"1"59;
"B"
$PN"2"58;
%"CAP"
"2","(-4850,4250)","0","mstr_discrete","I180";
;
PART_NUMBER"A36096-155"
PACK_TYPE"0402"
VOLTAGE"16V"
MATERIAL"X7R"
TOLERANCE"10%"
VALUE"0.22UF"
LOCATION"C2T23"
CDS_SEC"1"
BOM_COST"ST_FLASH"
ROOM"M_2"
SEC_TYPE"0402"
SEC"1"
CDS_LIB"mstr_discrete"
CDS_LOCATION"C2T23";
"A"
$PN"1"57;
"B"
$PN"2"56;
%"RES"
"1","(-2850,2925)","0","mstr_discrete","I183";
;
VALUE"0.0"
PACK_TYPE"0402"
MATERIAL"CHIP"
PART_NUMBER"G21497-005"
WATTAGE"1/16W"
TOLERANCE"5%"
LOCATION"R32W10"
CDS_SEC"1"
ROOM"IO_SLOT"
SEC"1"
CDS_LIB"mstr_discrete"
SEC_TYPE"0402"
CDS_LOCATION"R32W10";
"B"
$PN"2"79;
"A"
$PN"1"92;
%"RES"
"1","(-2625,2875)","0","mstr_discrete","I184";
;
MATERIAL"CHIP"
PART_NUMBER"G21497-005"
VALUE"0.0"
TOLERANCE"5%"
WATTAGE"1/16W"
PACK_TYPE"0402"
LOCATION"R32W11"
SEC_TYPE"0402"
CDS_LIB"mstr_discrete"
SEC"1"
ROOM"IO_SLOT"
CDS_SEC"1"
CDS_LOCATION"R32W11";
"B"
$PN"2"55;
"A"
$PN"1"93;
%"GND"
"1","(-2450,3000)","0","mstr_symbols","I185";
;
ROOM"P2V5_LAN_AUX_VR"
BOM_COST"NT_BASE_VRD"
SIZE"1B"
CDS_LIB"mstr_symbols"
VOLTAGE"0"
BODY_TYPE"PLUMBING"
HDL_POWER"GND";
"A\NAC"25;
%"GND"
"1","(-2100,2725)","0","mstr_symbols","I186";
;
ROOM"P2V5_LAN_AUX_VR"
BOM_COST"NT_BASE_VRD"
SIZE"1B"
CDS_LIB"mstr_symbols"
VOLTAGE"0"
BODY_TYPE"PLUMBING"
HDL_POWER"GND";
"A\NAC"26;
%"RES"
"1","(-2675,3700)","0","mstr_discrete","I187";
;
MATERIAL"CHIP"
LOCATION"R32W12"
VALUE"0.0"
WATTAGE"1/16W"
PART_NUMBER"G21497-005"
TOLERANCE"5%"
PACK_TYPE"0402"
SEC_TYPE"0402"
CDS_LIB"mstr_discrete"
SEC"1"
ROOM"IO_SLOT"
CDS_SEC"1"
CDS_LOCATION"R32W12";
"B"
$PN"2"45;
"A"
$PN"1"78;
%"CAP_A"
"1","(-2450,3200)","0","dev_discrete","I188";
;
LOCATION"C32W1"
VALUE"0.1UF"
VOLTAGE"16V"
PACK_TYPE"0402V"
MATERIAL"X7R"
TOLERANCE"10%"
PART_NUMBER"A36096-030"
ROOM"SMB_PE_HP_CPU1"
SEC_TYPE"0402V"
SEC"1"
CDS_LIB"dev_discrete"
CDS_SEC"1"
CDS_LOCATION"C32W1";
"B"
$PN"2"25;
"A"
$PN"1"46;
%"GND"
"1","(-2100,3500)","0","mstr_symbols","I189";
;
HDL_POWER"GND"
BODY_TYPE"PLUMBING"
VOLTAGE"0"
CDS_LIB"mstr_symbols"
SIZE"1B"
BOM_COST"NT_BASE_VRD"
ROOM"P2V5_LAN_AUX_VR";
"A\NAC"27;
%"CAP_A"
"1","(-2450,3975)","0","dev_discrete","I190";
;
PART_NUMBER"A36096-030"
PACK_TYPE"0402V"
MATERIAL"X7R"
VOLTAGE"16V"
VALUE"0.1UF"
LOCATION"C32W3"
TOLERANCE"10%"
ROOM"SMB_PE_HP_CPU1"
SEC_TYPE"0402V"
SEC"1"
CDS_LIB"dev_discrete"
CDS_SEC"1"
CDS_LOCATION"C32W3";
"B"
$PN"2"33;
"A"
$PN"1"77;
%"TCA9517DGKR-GP"
"1","(-1725,2900)","0","w_hdl","I191";
;
VALUE"TCA9517DGKR-GP"
LOCATION"U32W1"
CDS_SEC"1"
PACK_TYPE"DISCRET-G8"
SEC"1"
SEC_TYPE"DISCRET-G8"
CDS_LMAN_SYM_OUTLINE"-175,175,175,-175"
CDS_LIB"w_hdl"
PART_NUMBER"071.09517.0009"
CDS_LOCATION"U32W1";
"EN"
$PN"5"44;
"SDAB"
$PN"6"47;
"SCLB"
$PN"7"99;
"VCCB"
$PN"8"29;
"GND"
$PN"4"26;
"SDAA"
$PN"3"55;
"SCLA"
$PN"2"79;
"VCCA"
$PN"1"46;
%"GND"
"1","(-1150,3000)","0","mstr_symbols","I192";
;
ROOM"P2V5_LAN_AUX_VR"
BOM_COST"NT_BASE_VRD"
SIZE"1B"
CDS_LIB"mstr_symbols"
VOLTAGE"0"
BODY_TYPE"PLUMBING"
HDL_POWER"GND";
"A\NAC"28;
%"CAP_A"
"1","(-1150,3200)","0","dev_discrete","I193";
;
PART_NUMBER"A36096-030"
VOLTAGE"16V"
MATERIAL"X7R"
TOLERANCE"10%"
PACK_TYPE"0402V"
VALUE"0.1UF"
LOCATION"C32W2"
ROOM"SMB_PE_HP_CPU1"
SEC_TYPE"0402V"
SEC"1"
CDS_LIB"dev_discrete"
CDS_SEC"1"
CDS_LOCATION"C32W2";
"B"
$PN"2"28;
"A"
$PN"1"29;
%"P3V3_STBY"
"1","(-1150,3450)","0","mstr_symbols","I194";
;
VOLTAGE"3.3V"
CDS_LIB"mstr_symbols"
SIZE"1B"
BODY_TYPE"PLUMBING"
HDL_POWER"P3V3_STBY";
"G\NAC"29;
%"GND"
"1","(-1200,3800)","0","mstr_symbols","I195";
;
ROOM"P2V5_LAN_AUX_VR"
BOM_COST"NT_BASE_VRD"
SIZE"1B"
CDS_LIB"mstr_symbols"
VOLTAGE"0"
BODY_TYPE"PLUMBING"
HDL_POWER"GND";
"A\NAC"30;
%"CAP_A"
"1","(-1200,4000)","0","dev_discrete","I196";
;
LOCATION"C32W4"
VALUE"0.1UF"
VOLTAGE"16V"
PACK_TYPE"0402V"
TOLERANCE"10%"
MATERIAL"X7R"
PART_NUMBER"A36096-030"
CDS_SEC"1"
CDS_LIB"dev_discrete"
SEC"1"
SEC_TYPE"0402V"
ROOM"SMB_PE_HP_CPU1"
CDS_LOCATION"C32W4";
"B"
$PN"2"30;
"A"
$PN"1"32;
%"GND"
"1","(-850,3250)","0","mstr_symbols","I199";
;
ROOM"P2V5_LAN_AUX_VR"
BOM_COST"NT_BASE_VRD"
SIZE"1B"
CDS_LIB"mstr_symbols"
VOLTAGE"0"
BODY_TYPE"PLUMBING"
HDL_POWER"GND";
"A\NAC"31;
%"RES"
"2","(-850,3450)","0","mstr_discrete","I200";
;
WATTAGE"1/16W"
TOLERANCE"1%"
LOCATION"R32W9"
VALUE"10.0K"
PART_NUMBER"G21796-016"
MATERIAL"CHIP"
PACK_TYPE"0402"
POP"NOPOP"
CDS_SEC"1"
SEC_TYPE"0402"
SEC"1"
BOM_COST"PROC_SIDEBAND"
CDS_LIB"mstr_discrete"
ROOM"CPU0"
CDS_LOCATION"R32W9";
"A"
$PN"1"44;
"B"
$PN"2"31;
%"P3V3_STBY"
"1","(-1300,4225)","0","mstr_symbols","I202";
;
VOLTAGE"3.3V"
CDS_LIB"mstr_symbols"
SIZE"1B"
BODY_TYPE"PLUMBING"
HDL_POWER"P3V3_STBY";
"G\NAC"32;
%"GND"
"1","(-2450,3775)","0","mstr_symbols","I203";
;
ROOM"P2V5_LAN_AUX_VR"
BOM_COST"NT_BASE_VRD"
SIZE"1B"
CDS_LIB"mstr_symbols"
VOLTAGE"0"
BODY_TYPE"PLUMBING"
HDL_POWER"GND";
"A\NAC"33;
%"TCA9517DGKR-GP"
"1","(-1725,3675)","0","w_hdl","I204";
;
LOCATION"U32W2"
VALUE"TCA9517DGKR-GP"
PART_NUMBER"071.09517.0009"
CDS_LIB"w_hdl"
CDS_LMAN_SYM_OUTLINE"-175,175,175,-175"
SEC_TYPE"DISCRET-G8"
SEC"1"
PACK_TYPE"DISCRET-G8"
CDS_SEC"1"
CDS_LOCATION"U32W2";
"EN"
$PN"5"44;
"SDAB"
$PN"6"0;
"SCLB"
$PN"7"76;
"VCCB"
$PN"8"32;
"GND"
$PN"4"27;
"SDAA"
$PN"3"0;
"SCLA"
$PN"2"45;
"VCCA"
$PN"1"77;
%"GND"
"1","(-7800,1175)","0","mstr_symbols","I205";
;
BODY_TYPE"PLUMBING"
SIZE"1B"
VOLTAGE"0.0V"
CDS_LIB"mstr_symbols"
HDL_POWER"GND";
"A\NAC"34;
%"RES"
"1","(-7800,1350)","5","mstr_discrete","I206";
;
WATTAGE"1/16W"
PACK_TYPE"0402"
VALUE"3.3K"
LOCATION"R32W3"
TOLERANCE"5%"
PART_NUMBER"G21497-013"
MATERIAL"CHIP"
CDS_SEC"1"
CDS_LOCATION"R32W3"
SEC"1"
SEC_TYPE"0402"
CDS_LIB"mstr_discrete";
"B"
$PN"2"34;
"A"
$PN"1"98;
%"RES"
"2","(-7800,1650)","0","mstr_discrete","I207";
;
PART_NUMBER"G21796-003"
VALUE"1.5K"
PACK_TYPE"0402"
MATERIAL"CHIP"
WATTAGE"1/16W"
TOLERANCE"1%"
LOCATION"R32W2"
CDS_SEC"1"
CDS_LOCATION"R32W2"
ROOM"PVCCIN_CPU0_VR"
SEC"1"
SEC_TYPE"0402"
CDS_LIB"mstr_discrete";
"A"
$PN"1"48;
"B"
$PN"2"98;
%"RES"
"2","(-7800,1950)","0","mstr_discrete","I208";
;
WATTAGE"1/16W"
TOLERANCE"1%"
MATERIAL"CHIP"
PACK_TYPE"0402"
PART_NUMBER"G21796-082"
VALUE"4.02K"
LOCATION"R32W1"
CDS_SEC"1"
CDS_LOCATION"R32W1"
SEC_TYPE"0402"
CDS_LIB"mstr_discrete"
SEC"1"
ROOM"PVCCIN_CPU1_VR";
"A"
$PN"1"35;
"B"
$PN"2"48;
%"P3V3"
"1","(-7800,2150)","0","mstr_symbols","I209";
;
VOLTAGE"3.3V"
SIZE"1B"
CDS_LIB"mstr_symbols"
BODY_TYPE"PLUMBING"
HDL_POWER"P3V3";
"G\NAC"35;
%"GND"
"1","(-7900,700)","0","mstr_symbols","I210";
;
HDL_POWER"GND"
CDS_LIB"mstr_symbols"
VOLTAGE"0.0V"
SIZE"1B"
BODY_TYPE"PLUMBING";
"A\NAC"36;
%"RES"
"2","(-7900,900)","0","mstr_discrete","I211";
;
POP"NOPOP"
LOCATION"R32W4"
MATERIAL"CHIP"
PART_NUMBER"G21796-048"
PACK_TYPE"0402"
VALUE"49.9K"
TOLERANCE"1%"
WATTAGE"1/16W"
SEC"1"
SEC_TYPE"0402"
ROOM"V_SUPER"
CDS_LIB"mstr_discrete"
CDS_LOCATION"R32W4"
CDS_SEC"1";
"A"
$PN"1"48;
"B"
$PN"2"36;
%"GND"
"1","(-6550,1300)","0","mstr_symbols","I212";
;
HDL_POWER"GND"
CDS_LIB"mstr_symbols"
VOLTAGE"0.0V"
SIZE"1B"
BODY_TYPE"PLUMBING";
"A\NAC"37;
%"LMV431AIMFX-GP"
"1","(-6900,1400)","0","w_hdl","I213";
;
PART_NUMBER"74.MV431.031"
VALUE"LMV431AIMFX-GP"
LOCATION"VR32W1"
CDS_SEC"1"
CDS_LOCATION"VR32W1"
CDS_LIB"w_hdl"
CDS_LMAN_SYM_OUTLINE"-200,150,200,-150"
PACK_TYPE"DISCRET-G5"
SEC"1"
SEC_TYPE"DISCRET-G5";
"ANODE"
$PN"3"37;
"CATHODE"
$PN"2"48;
"REF"
$PN"1"98;
%"RES"
"2","(-5450,1150)","0","mstr_discrete","I214";
;
PACK_TYPE"0402"
PART_NUMBER"G21796-001"
MATERIAL"CHIP"
WATTAGE"1/16W"
VALUE"2.0K"
LOCATION"R32W6"
TOLERANCE"1%"
CDS_LOCATION"R32W6"
CDS_SEC"1"
SEC"1"
SEC_TYPE"0402"
BOM_COST"SM_CONTROLLER"
ROOM"SMBUS"
CDS_LIB"mstr_discrete";
"A"
$PN"1"95;
"B"
$PN"2"96;
%"RES"
"2","(-5150,1150)","0","mstr_discrete","I215";
;
PACK_TYPE"0402"
MATERIAL"CHIP"
WATTAGE"1/16W"
TOLERANCE"1%"
VALUE"2.0K"
PART_NUMBER"G21796-001"
LOCATION"R32W7"
CDS_LOCATION"R32W7"
CDS_SEC"1"
SEC"1"
SEC_TYPE"0402"
BOM_COST"SM_CONTROLLER"
ROOM"SMBUS"
CDS_LIB"mstr_discrete";
"A"
$PN"1"95;
"B"
$PN"2"75;
%"RES"
"2","(-5750,1150)","0","mstr_discrete","I216";
;
TOLERANCE"1%"
WATTAGE"1/16W"
LOCATION"R32W5"
PACK_TYPE"0402"
VALUE"2.0K"
PART_NUMBER"G21796-001"
MATERIAL"CHIP"
CDS_LOCATION"R32W5"
CDS_SEC"1"
SEC"1"
SEC_TYPE"0402"
BOM_COST"SM_CONTROLLER"
ROOM"SMBUS"
CDS_LIB"mstr_discrete";
"A"
$PN"1"95;
"B"
$PN"2"97;
%"CAP"
"1","(-7300,900)","0","mstr_discrete","I217";
;
CDS_SEC"1"
CDS_LOCATION"C32W5"
PART_NUMBER"D97712-011"
LOCATION"C32W5"
PACK_TYPE"0402"
MATERIAL"X6S"
VALUE"1.0UF"
VOLTAGE"16V"
TOLERANCE"10%"
POP"NOPOP"
SEC_TYPE"0402"
SEC"1"
CDS_LIB"mstr_discrete"
ROOM"PROC_SIDEBAND"
BOM_COST"PROC";
"A"
$PN"1"48;
"B"
$PN"2"38;
%"GND"
"1","(-7300,700)","0","mstr_symbols","I218";
;
BODY_TYPE"PLUMBING"
SIZE"1B"
VOLTAGE"0.0V"
CDS_LIB"mstr_symbols"
HDL_POWER"GND";
"A\NAC"38;
%"CAP"
"2","(-2575,1825)","0","mstr_discrete","I96";
;
CDS_SEC"1"
VOLTAGE"16V"
MATERIAL"X7R"
PACK_TYPE"0402"
PART_NUMBER"A36096-155"
LOCATION"C8F7"
VALUE"0.22UF"
GROUP"M2_PCIE"
TOLERANCE"10%"
CDS_LOCATION"C8F7"
CDS_LIB"mstr_discrete"
ROOM"M_2"
BOM_COST"ST_FLASH"
SEC_TYPE"0402"
SEC"1";
"A"
$PN"1"90;
"B"
$PN"2"104;
END.
